(kicad_pcb
	(version 20260206)
	(generator "pcbnew")
	(generator_version "10.0")
	(general
		(thickness 1.6)
		(legacy_teardrops no)
	)
	(paper "A4")
	(title_block
		(title "01162023_DA0F0TEBIF0_F0T_Expander_BD_F_brd_V02_OCP.brd")
		(comment 1 "Grand Teton / footprints 7760-7768 of 9728")
	)
	(layers
		(0 "F.Cu" signal "TOP")
		(4 "In1.Cu" signal "GND")
		(6 "In2.Cu" signal "VCC")
		(8 "In3.Cu" signal "VCC1")
		(10 "In4.Cu" signal "GND1")
		(12 "In5.Cu" signal "IN1")
		(14 "In6.Cu" signal "GND2")
		(16 "In7.Cu" signal "IN2")
		(18 "In8.Cu" signal "GND3")
		(20 "In9.Cu" signal "IN3")
		(22 "In10.Cu" signal "GND4")
		(24 "In11.Cu" signal "IN4")
		(26 "In12.Cu" signal "GND5")
		(28 "In13.Cu" signal "IN5")
		(30 "In14.Cu" signal "GND6")
		(32 "In15.Cu" signal "IN6")
		(34 "In16.Cu" signal "GND7")
		(2 "B.Cu" signal "BOTTOM")
		(9 "F.Adhes" user "F.Adhesive")
		(11 "B.Adhes" user "B.Adhesive")
		(13 "F.Paste" user "Package Geometry/Pastemask Top")
		(15 "B.Paste" user "Package Geometry/Pastemask Bottom")
		(5 "F.SilkS" user "Ref Des/Silkscreen Top")
		(7 "B.SilkS" user "Ref Des/Silkscreen Bottom")
		(1 "F.Mask" user "Board Geometry/Soldermask Top")
		(3 "B.Mask" user "Board Geometry/Soldermask Bottom")
		(17 "Dwgs.User" user "User.Drawings")
		(19 "Cmts.User" user "User.Comments")
		(21 "Eco1.User" user "User.Eco1")
		(23 "Eco2.User" user "User.Eco2")
		(25 "Edge.Cuts" user "Board Geometry/Outline")
		(27 "Margin" user)
		(31 "F.CrtYd" user "Package Geometry/Place Bound Top")
		(29 "B.CrtYd" user "Package Geometry/Place Bound Bottom")
		(35 "F.Fab" user "Ref Des/Assembly Top")
		(33 "B.Fab" user "Ref Des/Assembly Bottom")
	)
	(footprint ""
		(layer "B.Cu")
		(at 400.824954 -293.99992 90)
		(property "Reference" "C1903"
			(at 0 0 90)
			(layer "B.SilkS")
			(hide yes)
			(effects
				(font
					(size 1.27 1.27)
				)
				(justify mirror)
			)
		)
		(property "Value" ""
			(at 0 0 90)
			(layer "B.Fab")
			(effects
				(font
					(size 1.27 1.27)
				)
				(justify mirror)
			)
		)
		(duplicate_pad_numbers_are_jumpers no)
		(fp_line
			(start 0.299974 -0.150114)
			(end -0.299974 -0.150114)
			(stroke
				(width 0.1)
				(type default)
			)
			(layer "B.Fab")
		)
		(fp_line
			(start -0.299974 -0.150114)
			(end -0.299974 0.150114)
			(stroke
				(width 0.1)
				(type default)
			)
			(layer "B.Fab")
		)
		(fp_line
			(start 0.299974 0.150114)
			(end 0.299974 -0.150114)
			(stroke
				(width 0.1)
				(type default)
			)
			(layer "B.Fab")
		)
		(fp_line
			(start -0.299974 0.150114)
			(end 0.299974 0.150114)
			(stroke
				(width 0.1)
				(type default)
			)
			(layer "B.Fab")
		)
		(pad "1" smd rect
			(at 0.2667 0 270)
			(size 0.3048 0.381)
			(layers "B.Cu" "B.Mask" "B.Paste")
			(net "P0V8_PEX3")
		)
		(pad "2" smd rect
			(at -0.2667 0 270)
			(size 0.3048 0.381)
			(layers "B.Cu" "B.Mask" "B.Paste")
			(net "GND")
		)
	)
	(footprint ""
		(layer "B.Cu")
		(at 305.149758 -295.89984 180)
		(property "Reference" "C3316"
			(at 0 0 0)
			(layer "B.SilkS")
			(hide yes)
			(effects
				(font
					(size 1.27 1.27)
				)
				(justify mirror)
			)
		)
		(property "Value" ""
			(at 0 0 0)
			(layer "B.Fab")
			(effects
				(font
					(size 1.27 1.27)
				)
				(justify mirror)
			)
		)
		(duplicate_pad_numbers_are_jumpers no)
		(fp_line
			(start 0.299974 0.150114)
			(end 0.299974 -0.150114)
			(stroke
				(width 0.1)
				(type default)
			)
			(layer "B.Fab")
		)
		(fp_line
			(start 0.299974 -0.150114)
			(end -0.299974 -0.150114)
			(stroke
				(width 0.1)
				(type default)
			)
			(layer "B.Fab")
		)
		(fp_line
			(start -0.299974 0.150114)
			(end 0.299974 0.150114)
			(stroke
				(width 0.1)
				(type default)
			)
			(layer "B.Fab")
		)
		(fp_line
			(start -0.299974 -0.150114)
			(end -0.299974 0.150114)
			(stroke
				(width 0.1)
				(type default)
			)
			(layer "B.Fab")
		)
		(pad "1" smd rect
			(at 0.2667 0)
			(size 0.3048 0.381)
			(layers "B.Cu" "B.Mask" "B.Paste")
			(net "P1V25_SERDES_VDDPLL_PEX2")
		)
		(pad "2" smd rect
			(at -0.2667 0)
			(size 0.3048 0.381)
			(layers "B.Cu" "B.Mask" "B.Paste")
			(net "GND")
		)
	)
	(footprint ""
		(layer "B.Cu")
		(at 223.761046 -153.127202 90)
		(property "Reference" "L81"
			(at 0 0 90)
			(layer "B.SilkS")
			(hide yes)
			(effects
				(font
					(size 1.27 1.27)
				)
				(justify mirror)
			)
		)
		(property "Value" ""
			(at 0 0 90)
			(layer "B.Fab")
			(effects
				(font
					(size 1.27 1.27)
				)
				(justify mirror)
			)
		)
		(duplicate_pad_numbers_are_jumpers no)
		(fp_line
			(start 1.63576 -0.8128)
			(end -1.63576 -0.8128)
			(stroke
				(width 0.1524)
				(type default)
			)
			(layer "B.SilkS")
		)
		(fp_line
			(start 1.63576 -0.8128)
			(end 1.63576 0.8128)
			(stroke
				(width 0.1524)
				(type default)
			)
			(layer "B.SilkS")
		)
		(fp_line
			(start -1.63576 -0.8128)
			(end -1.63576 0.8128)
			(stroke
				(width 0.1524)
				(type default)
			)
			(layer "B.SilkS")
		)
		(fp_line
			(start -1.63576 0.8128)
			(end 1.63576 0.8128)
			(stroke
				(width 0.1524)
				(type default)
			)
			(layer "B.SilkS")
		)
		(fp_line
			(start 1.56083 -0.738632)
			(end 1.56083 0.7366)
			(stroke
				(width 0.1)
				(type default)
			)
			(layer "B.Fab")
		)
		(fp_line
			(start -1.560576 -0.738632)
			(end 1.56083 -0.738632)
			(stroke
				(width 0.1)
				(type default)
			)
			(layer "B.Fab")
		)
		(fp_line
			(start 1.56083 0.7366)
			(end 1.524 0.7366)
			(stroke
				(width 0.1)
				(type default)
			)
			(layer "B.Fab")
		)
		(fp_line
			(start 1.524 0.7366)
			(end -1.524 0.7366)
			(stroke
				(width 0.1)
				(type default)
			)
			(layer "B.Fab")
		)
		(fp_line
			(start -1.524 0.7366)
			(end -1.560576 0.7366)
			(stroke
				(width 0.1)
				(type default)
			)
			(layer "B.Fab")
		)
		(fp_line
			(start -1.560576 0.7366)
			(end -1.560576 -0.738632)
			(stroke
				(width 0.1)
				(type default)
			)
			(layer "B.Fab")
		)
		(pad "1" smd rect
			(at 0.94996 0 90)
			(size 1.1176 1.3716)
			(layers "B.Cu" "B.Mask" "B.Paste")
			(net "P3V3")
		)
		(pad "2" smd rect
			(at -0.94996 0 90)
			(size 1.1176 1.3716)
			(layers "B.Cu" "B.Mask" "B.Paste")
			(net "P3V3_CLK_GEN_VDDMXCK_CK440_PEX")
		)
	)
	(footprint ""
		(layer "B.Cu")
		(at 395.03604 -298.27474)
		(property "Reference" "C3591"
			(at 0 0 0)
			(layer "B.SilkS")
			(hide yes)
			(effects
				(font
					(size 1.27 1.27)
				)
				(justify mirror)
			)
		)
		(property "Value" ""
			(at 0 0 0)
			(layer "B.Fab")
			(effects
				(font
					(size 1.27 1.27)
				)
				(justify mirror)
			)
		)
		(duplicate_pad_numbers_are_jumpers no)
		(fp_line
			(start -0.299974 -0.150114)
			(end -0.299974 0.150114)
			(stroke
				(width 0.1)
				(type default)
			)
			(layer "B.Fab")
		)
		(fp_line
			(start -0.299974 0.150114)
			(end 0.299974 0.150114)
			(stroke
				(width 0.1)
				(type default)
			)
			(layer "B.Fab")
		)
		(fp_line
			(start 0.299974 -0.150114)
			(end -0.299974 -0.150114)
			(stroke
				(width 0.1)
				(type default)
			)
			(layer "B.Fab")
		)
		(fp_line
			(start 0.299974 0.150114)
			(end 0.299974 -0.150114)
			(stroke
				(width 0.1)
				(type default)
			)
			(layer "B.Fab")
		)
		(pad "1" smd rect
			(at 0.2667 0 180)
			(size 0.3048 0.381)
			(layers "B.Cu" "B.Mask" "B.Paste")
			(net "SYSPLL_VDDA18_PEX3")
		)
		(pad "2" smd rect
			(at -0.2667 0 180)
			(size 0.3048 0.381)
			(layers "B.Cu" "B.Mask" "B.Paste")
			(net "GND")
		)
	)
	(footprint ""
		(layer "B.Cu")
		(at 394.164312 -143.608552 180)
		(property "Reference" "C938"
			(at 0 0 0)
			(layer "B.SilkS")
			(hide yes)
			(effects
				(font
					(size 1.27 1.27)
				)
				(justify mirror)
			)
		)
		(property "Value" ""
			(at 0 0 0)
			(layer "B.Fab")
			(effects
				(font
					(size 1.27 1.27)
				)
				(justify mirror)
			)
		)
		(duplicate_pad_numbers_are_jumpers no)
		(fp_line
			(start 0.299974 0.150114)
			(end 0.299974 -0.150114)
			(stroke
				(width 0.1)
				(type default)
			)
			(layer "B.Fab")
		)
		(fp_line
			(start 0.299974 -0.150114)
			(end -0.299974 -0.150114)
			(stroke
				(width 0.1)
				(type default)
			)
			(layer "B.Fab")
		)
		(fp_line
			(start -0.299974 0.150114)
			(end 0.299974 0.150114)
			(stroke
				(width 0.1)
				(type default)
			)
			(layer "B.Fab")
		)
		(fp_line
			(start -0.299974 -0.150114)
			(end -0.299974 0.150114)
			(stroke
				(width 0.1)
				(type default)
			)
			(layer "B.Fab")
		)
		(pad "1" smd rect
			(at 0.2667 0)
			(size 0.3048 0.381)
			(layers "B.Cu" "B.Mask" "B.Paste")
			(net "P12V_NIC6")
		)
		(pad "2" smd rect
			(at -0.2667 0)
			(size 0.3048 0.381)
			(layers "B.Cu" "B.Mask" "B.Paste")
			(net "GND")
		)
	)
	(footprint ""
		(layer "B.Cu")
		(at 458.073506 -250.20524)
		(property "Reference" "R6587"
			(at 0 0 0)
			(layer "B.SilkS")
			(hide yes)
			(effects
				(font
					(size 1.27 1.27)
				)
				(justify mirror)
			)
		)
		(property "Value" ""
			(at 0 0 0)
			(layer "B.Fab")
			(effects
				(font
					(size 1.27 1.27)
				)
				(justify mirror)
			)
		)
		(duplicate_pad_numbers_are_jumpers no)
		(fp_line
			(start -0.7874 -0.4064)
			(end -0.7874 0.4064)
			(stroke
				(width 0.1524)
				(type default)
			)
			(layer "B.SilkS")
		)
		(fp_line
			(start -0.7874 0.4064)
			(end 0.7874 0.4064)
			(stroke
				(width 0.1524)
				(type default)
			)
			(layer "B.SilkS")
		)
		(fp_line
			(start 0.7874 -0.4064)
			(end -0.7874 -0.4064)
			(stroke
				(width 0.1524)
				(type default)
			)
			(layer "B.SilkS")
		)
		(fp_line
			(start 0.7874 0.4064)
			(end 0.7874 -0.4064)
			(stroke
				(width 0.1524)
				(type default)
			)
			(layer "B.SilkS")
		)
		(fp_line
			(start -0.67945 -0.3048)
			(end -0.67945 0.3048)
			(stroke
				(width 0.1)
				(type default)
			)
			(layer "B.Fab")
		)
		(fp_line
			(start -0.67945 0.3048)
			(end -0.120396 0.3048)
			(stroke
				(width 0.1)
				(type default)
			)
			(layer "B.Fab")
		)
		(fp_line
			(start -0.12065 -0.3048)
			(end -0.67945 -0.3048)
			(stroke
				(width 0.1)
				(type default)
			)
			(layer "B.Fab")
		)
		(fp_line
			(start -0.12065 -0.2794)
			(end -0.12065 -0.3048)
			(stroke
				(width 0.1)
				(type default)
			)
			(layer "B.Fab")
		)
		(fp_line
			(start -0.120396 0.2794)
			(end 0.12065 0.2794)
			(stroke
				(width 0.1)
				(type default)
			)
			(layer "B.Fab")
		)
		(fp_line
			(start -0.120396 0.3048)
			(end -0.120396 0.2794)
			(stroke
				(width 0.1)
				(type default)
			)
			(layer "B.Fab")
		)
		(fp_line
			(start 0.12065 -0.305054)
			(end 0.12065 -0.2794)
			(stroke
				(width 0.1)
				(type default)
			)
			(layer "B.Fab")
		)
		(fp_line
			(start 0.12065 -0.2794)
			(end -0.12065 -0.2794)
			(stroke
				(width 0.1)
				(type default)
			)
			(layer "B.Fab")
		)
		(fp_line
			(start 0.12065 0.2794)
			(end 0.12065 0.3048)
			(stroke
				(width 0.1)
				(type default)
			)
			(layer "B.Fab")
		)
		(fp_line
			(start 0.12065 0.3048)
			(end 0.67945 0.3048)
			(stroke
				(width 0.1)
				(type default)
			)
			(layer "B.Fab")
		)
		(fp_line
			(start 0.67945 -0.305054)
			(end 0.12065 -0.305054)
			(stroke
				(width 0.1)
				(type default)
			)
			(layer "B.Fab")
		)
		(fp_line
			(start 0.67945 0.3048)
			(end 0.67945 -0.305054)
			(stroke
				(width 0.1)
				(type default)
			)
			(layer "B.Fab")
		)
		(pad "1" smd circle
			(at 0.40005 0 180)
			(size 0 0)
			(layers "B.Cu" "B.Mask" "B.Paste")
			(net "P3V3_AUX")
		)
		(pad "2" smd circle
			(at -0.40005 0 180)
			(size 0 0)
			(layers "B.Cu" "B.Mask" "B.Paste")
			(net "PWRGD_PEX3_P1V8_PLL")
		)
	)
	(footprint ""
		(layer "B.Cu")
		(at 104.601264 -308.580028 90)
		(property "Reference" "C4197"
			(at 0 0 90)
			(layer "B.SilkS")
			(hide yes)
			(effects
				(font
					(size 1.27 1.27)
				)
				(justify mirror)
			)
		)
		(property "Value" ""
			(at 0 0 90)
			(layer "B.Fab")
			(effects
				(font
					(size 1.27 1.27)
				)
				(justify mirror)
			)
		)
		(duplicate_pad_numbers_are_jumpers no)
		(fp_line
			(start 1.2954 -0.5842)
			(end -1.2954 -0.5842)
			(stroke
				(width 0.1524)
				(type default)
			)
			(layer "B.SilkS")
		)
		(fp_line
			(start -1.2954 -0.5842)
			(end -1.2954 0.5842)
			(stroke
				(width 0.1524)
				(type default)
			)
			(layer "B.SilkS")
		)
		(fp_line
			(start 1.2954 0.5842)
			(end 1.2954 -0.5842)
			(stroke
				(width 0.1524)
				(type default)
			)
			(layer "B.SilkS")
		)
		(fp_line
			(start -1.2954 0.5842)
			(end 1.2954 0.5842)
			(stroke
				(width 0.1524)
				(type default)
			)
			(layer "B.SilkS")
		)
		(fp_line
			(start 0.8636 -0.4572)
			(end -0.8636 -0.4572)
			(stroke
				(width 0.1)
				(type default)
			)
			(layer "B.Fab")
		)
		(fp_line
			(start -0.8636 -0.4572)
			(end -0.8636 -0.4064)
			(stroke
				(width 0.1)
				(type default)
			)
			(layer "B.Fab")
		)
		(fp_line
			(start 1.1938 -0.4064)
			(end 0.8636 -0.4064)
			(stroke
				(width 0.1)
				(type default)
			)
			(layer "B.Fab")
		)
		(fp_line
			(start 0.8636 -0.4064)
			(end 0.8636 -0.4572)
			(stroke
				(width 0.1)
				(type default)
			)
			(layer "B.Fab")
		)
		(fp_line
			(start -0.8636 -0.4064)
			(end -1.1938 -0.4064)
			(stroke
				(width 0.1)
				(type default)
			)
			(layer "B.Fab")
		)
		(fp_line
			(start -1.1938 -0.4064)
			(end -1.1938 0.4064)
			(stroke
				(width 0.1)
				(type default)
			)
			(layer "B.Fab")
		)
		(fp_line
			(start 1.1938 0.4064)
			(end 1.1938 -0.4064)
			(stroke
				(width 0.1)
				(type default)
			)
			(layer "B.Fab")
		)
		(fp_line
			(start 0.8636 0.4064)
			(end 1.1938 0.4064)
			(stroke
				(width 0.1)
				(type default)
			)
			(layer "B.Fab")
		)
		(fp_line
			(start -0.8636 0.4064)
			(end -0.8636 0.4572)
			(stroke
				(width 0.1)
				(type default)
			)
			(layer "B.Fab")
		)
		(fp_line
			(start -1.1938 0.4064)
			(end -0.8636 0.4064)
			(stroke
				(width 0.1)
				(type default)
			)
			(layer "B.Fab")
		)
		(fp_line
			(start 0.8636 0.4572)
			(end 0.8636 0.4064)
			(stroke
				(width 0.1)
				(type default)
			)
			(layer "B.Fab")
		)
		(fp_line
			(start -0.8636 0.4572)
			(end 0.8636 0.4572)
			(stroke
				(width 0.1)
				(type default)
			)
			(layer "B.Fab")
		)
		(pad "1" smd rect
			(at 0.7366 0)
			(size 0.7112 0.8128)
			(layers "B.Cu" "B.Mask" "B.Paste")
			(net "P0V8_PEX0")
		)
		(pad "2" smd rect
			(at -0.7366 0)
			(size 0.7112 0.8128)
			(layers "B.Cu" "B.Mask" "B.Paste")
			(net "GND")
		)
	)
	(footprint ""
		(layer "B.Cu")
		(at 351.645982 -156.337 180)
		(property "Reference" "R4797"
			(at 0 0 0)
			(layer "B.SilkS")
			(hide yes)
			(effects
				(font
					(size 1.27 1.27)
				)
				(justify mirror)
			)
		)
		(property "Value" ""
			(at 0 0 0)
			(layer "B.Fab")
			(effects
				(font
					(size 1.27 1.27)
				)
				(justify mirror)
			)
		)
		(duplicate_pad_numbers_are_jumpers no)
		(fp_line
			(start 0.7874 0.4064)
			(end 0.7874 -0.4064)
			(stroke
				(width 0.1524)
				(type default)
			)
			(layer "B.SilkS")
		)
		(fp_line
			(start 0.7874 -0.4064)
			(end -0.7874 -0.4064)
			(stroke
				(width 0.1524)
				(type default)
			)
			(layer "B.SilkS")
		)
		(fp_line
			(start -0.7874 0.4064)
			(end 0.7874 0.4064)
			(stroke
				(width 0.1524)
				(type default)
			)
			(layer "B.SilkS")
		)
		(fp_line
			(start -0.7874 -0.4064)
			(end -0.7874 0.4064)
			(stroke
				(width 0.1524)
				(type default)
			)
			(layer "B.SilkS")
		)
		(fp_line
			(start 0.67945 0.3048)
			(end 0.67945 -0.305054)
			(stroke
				(width 0.1)
				(type default)
			)
			(layer "B.Fab")
		)
		(fp_line
			(start 0.67945 -0.305054)
			(end 0.12065 -0.305054)
			(stroke
				(width 0.1)
				(type default)
			)
			(layer "B.Fab")
		)
		(fp_line
			(start 0.12065 0.3048)
			(end 0.67945 0.3048)
			(stroke
				(width 0.1)
				(type default)
			)
			(layer "B.Fab")
		)
		(fp_line
			(start 0.12065 0.2794)
			(end 0.12065 0.3048)
			(stroke
				(width 0.1)
				(type default)
			)
			(layer "B.Fab")
		)
		(fp_line
			(start 0.12065 -0.2794)
			(end -0.12065 -0.2794)
			(stroke
				(width 0.1)
				(type default)
			)
			(layer "B.Fab")
		)
		(fp_line
			(start 0.12065 -0.305054)
			(end 0.12065 -0.2794)
			(stroke
				(width 0.1)
				(type default)
			)
			(layer "B.Fab")
		)
		(fp_line
			(start -0.120396 0.3048)
			(end -0.120396 0.2794)
			(stroke
				(width 0.1)
				(type default)
			)
			(layer "B.Fab")
		)
		(fp_line
			(start -0.120396 0.2794)
			(end 0.12065 0.2794)
			(stroke
				(width 0.1)
				(type default)
			)
			(layer "B.Fab")
		)
		(fp_line
			(start -0.12065 -0.2794)
			(end -0.12065 -0.3048)
			(stroke
				(width 0.1)
				(type default)
			)
			(layer "B.Fab")
		)
		(fp_line
			(start -0.12065 -0.3048)
			(end -0.67945 -0.3048)
			(stroke
				(width 0.1)
				(type default)
			)
			(layer "B.Fab")
		)
		(fp_line
			(start -0.67945 0.3048)
			(end -0.120396 0.3048)
			(stroke
				(width 0.1)
				(type default)
			)
			(layer "B.Fab")
		)
		(fp_line
			(start -0.67945 -0.3048)
			(end -0.67945 0.3048)
			(stroke
				(width 0.1)
				(type default)
			)
			(layer "B.Fab")
		)
		(pad "1" smd circle
			(at 0.40005 0)
			(size 0 0)
			(layers "B.Cu" "B.Mask" "B.Paste")
			(net "P3V3_AUX")
		)
		(pad "2" smd circle
			(at -0.40005 0)
			(size 0 0)
			(layers "B.Cu" "B.Mask" "B.Paste")
			(net "RST_PEX_NIC6_PERST_R_N")
		)
	)
	(footprint ""
		(layer "B.Cu")
		(at 183.3499 -296.37482)
		(property "Reference" "C1448"
			(at 0 0 0)
			(layer "B.SilkS")
			(hide yes)
			(effects
				(font
					(size 1.27 1.27)
				)
				(justify mirror)
			)
		)
		(property "Value" ""
			(at 0 0 0)
			(layer "B.Fab")
			(effects
				(font
					(size 1.27 1.27)
				)
				(justify mirror)
			)
		)
		(duplicate_pad_numbers_are_jumpers no)
		(fp_line
			(start -0.299974 -0.150114)
			(end -0.299974 0.150114)
			(stroke
				(width 0.1)
				(type default)
			)
			(layer "B.Fab")
		)
		(fp_line
			(start -0.299974 0.150114)
			(end 0.299974 0.150114)
			(stroke
				(width 0.1)
				(type default)
			)
			(layer "B.Fab")
		)
		(fp_line
			(start 0.299974 -0.150114)
			(end -0.299974 -0.150114)
			(stroke
				(width 0.1)
				(type default)
			)
			(layer "B.Fab")
		)
		(fp_line
			(start 0.299974 0.150114)
			(end 0.299974 -0.150114)
			(stroke
				(width 0.1)
				(type default)
			)
			(layer "B.Fab")
		)
		(pad "1" smd rect
			(at 0.2667 0 180)
			(size 0.3048 0.381)
			(layers "B.Cu" "B.Mask" "B.Paste")
			(net "P0V8_SERDES_VDDA_PEX1")
		)
		(pad "2" smd rect
			(at -0.2667 0 180)
			(size 0.3048 0.381)
			(layers "B.Cu" "B.Mask" "B.Paste")
			(net "GND")
		)
	)
)
